# S9S_MB_2U (Grand Teton) — schematic netlist excerpt (pin names and nets, part order shuffled) for the footprints in the layout excerpt that follows; sources: Cadence DE-HDL packaged netlist, KiCad conversion of 03242023_DA0F0TMBIJ0_F0T_Motherboard_J_brd_V01_OCP.brd

C34  Q_CAP  10UF 16V 10% X6S  pkg C0805  page 92 : A = P12V_S3_AUX_CPU0_NVDIMM ; B = GND
PR158  Q_RES  0 5% CHIP  pkg 0402LF  page 266 : A = PVCCIN_CPU0_CSPIN ; B = GND
PC1421  Q_CAP  0.01UF 25V 10% X7R  pkg 0402  page 281 : A = SH_PVPP_HBM_CPU0_P ; B = SH_PVPP_HBM_CPU0_N

(kicad_pcb
	(version 20260206)
	(generator "pcbnew")
	(generator_version "10.0")
	(general
		(thickness 1.6)
		(legacy_teardrops no)
	)
	(paper "A4")
	(title_block
		(title "03242023_DA0F0TMBIJ0_F0T_Motherboard_J_brd_V01_OCP.brd")
		(comment 1 "Grand Teton / footprints 5708-5710 of 6105")
	)
	(layers
		(0 "F.Cu" signal "TOP")
		(4 "In1.Cu" signal "GND")
		(6 "In2.Cu" signal "IN1")
		(8 "In3.Cu" signal "GND1")
		(10 "In4.Cu" signal "IN2")
		(12 "In5.Cu" signal "GND2")
		(14 "In6.Cu" signal "IN3")
		(16 "In7.Cu" signal "GND3")
		(18 "In8.Cu" signal "VCC")
		(20 "In9.Cu" signal "VCC1")
		(22 "In10.Cu" signal "GND4")
		(24 "In11.Cu" signal "IN4")
		(26 "In12.Cu" signal "GND5")
		(28 "In13.Cu" signal "IN5")
		(30 "In14.Cu" signal "GND6")
		(32 "In15.Cu" signal "IN6")
		(34 "In16.Cu" signal "GND7")
		(2 "B.Cu" signal "BOTTOM")
		(9 "F.Adhes" user "F.Adhesive")
		(11 "B.Adhes" user "B.Adhesive")
		(13 "F.Paste" user "Package Geometry/Pastemask Top")
		(15 "B.Paste" user "Package Geometry/Pastemask Bottom")
		(5 "F.SilkS" user "Ref Des/Silkscreen Top")
		(7 "B.SilkS" user "Ref Des/Silkscreen Bottom")
		(1 "F.Mask" user "Board Geometry/Soldermask Top")
		(3 "B.Mask" user "Board Geometry/Soldermask Bottom")
		(17 "Dwgs.User" user "User.Drawings")
		(19 "Cmts.User" user "User.Comments")
		(21 "Eco1.User" user "User.Eco1")
		(23 "Eco2.User" user "User.Eco2")
		(25 "Edge.Cuts" user "Board Geometry/Outline")
		(27 "Margin" user)
		(31 "F.CrtYd" user "Package Geometry/Place Bound Top")
		(29 "B.CrtYd" user "Package Geometry/Place Bound Bottom")
		(35 "F.Fab" user "Ref Des/Assembly Top")
		(33 "B.Fab" user "Ref Des/Assembly Bottom")
	)
	(footprint ""
		(layer "B.Cu")
		(at 358.80675 -359.47985)
		(property "Reference" "PR158"
			(at 0 0 0)
			(layer "B.SilkS")
			(hide yes)
			(effects
				(font
					(size 1.27 1.27)
				)
				(justify mirror)
			)
		)
		(property "Value" ""
			(at 0 0 0)
			(layer "B.Fab")
			(effects
				(font
					(size 1.27 1.27)
				)
				(justify mirror)
			)
		)
		(duplicate_pad_numbers_are_jumpers no)
		(fp_line
			(start -0.7874 -0.4064)
			(end -0.7874 0.4064)
			(stroke
				(width 0.1524)
				(type default)
			)
			(layer "B.SilkS")
		)
		(fp_line
			(start -0.7874 0.4064)
			(end 0.7874 0.4064)
			(stroke
				(width 0.1524)
				(type default)
			)
			(layer "B.SilkS")
		)
		(fp_line
			(start 0.7874 -0.4064)
			(end -0.7874 -0.4064)
			(stroke
				(width 0.1524)
				(type default)
			)
			(layer "B.SilkS")
		)
		(fp_line
			(start 0.7874 0.4064)
			(end 0.7874 -0.4064)
			(stroke
				(width 0.1524)
				(type default)
			)
			(layer "B.SilkS")
		)
		(fp_line
			(start -0.67945 -0.3048)
			(end -0.67945 0.3048)
			(stroke
				(width 0.1)
				(type default)
			)
			(layer "B.Fab")
		)
		(fp_line
			(start -0.67945 0.3048)
			(end -0.120396 0.3048)
			(stroke
				(width 0.1)
				(type default)
			)
			(layer "B.Fab")
		)
		(fp_line
			(start -0.12065 -0.3048)
			(end -0.67945 -0.3048)
			(stroke
				(width 0.1)
				(type default)
			)
			(layer "B.Fab")
		)
		(fp_line
			(start -0.12065 -0.2794)
			(end -0.12065 -0.3048)
			(stroke
				(width 0.1)
				(type default)
			)
			(layer "B.Fab")
		)
		(fp_line
			(start -0.120396 0.2794)
			(end 0.12065 0.2794)
			(stroke
				(width 0.1)
				(type default)
			)
			(layer "B.Fab")
		)
		(fp_line
			(start -0.120396 0.3048)
			(end -0.120396 0.2794)
			(stroke
				(width 0.1)
				(type default)
			)
			(layer "B.Fab")
		)
		(fp_line
			(start 0.12065 -0.305054)
			(end 0.12065 -0.2794)
			(stroke
				(width 0.1)
				(type default)
			)
			(layer "B.Fab")
		)
		(fp_line
			(start 0.12065 -0.2794)
			(end -0.12065 -0.2794)
			(stroke
				(width 0.1)
				(type default)
			)
			(layer "B.Fab")
		)
		(fp_line
			(start 0.12065 0.2794)
			(end 0.12065 0.3048)
			(stroke
				(width 0.1)
				(type default)
			)
			(layer "B.Fab")
		)
		(fp_line
			(start 0.12065 0.3048)
			(end 0.67945 0.3048)
			(stroke
				(width 0.1)
				(type default)
			)
			(layer "B.Fab")
		)
		(fp_line
			(start 0.67945 -0.305054)
			(end 0.12065 -0.305054)
			(stroke
				(width 0.1)
				(type default)
			)
			(layer "B.Fab")
		)
		(fp_line
			(start 0.67945 0.3048)
			(end 0.67945 -0.305054)
			(stroke
				(width 0.1)
				(type default)
			)
			(layer "B.Fab")
		)
		(pad "1" smd circle
			(at 0.40005 0 180)
			(size 0 0)
			(layers "B.Cu" "B.Mask" "B.Paste")
			(net "PVCCIN_CPU0_CSPIN")
		)
		(pad "2" smd circle
			(at -0.40005 0 180)
			(size 0 0)
			(layers "B.Cu" "B.Mask" "B.Paste")
			(net "GND")
		)
	)
	(footprint ""
		(layer "B.Cu")
		(at 433.461414 -321.549776 -90)
		(property "Reference" "C34"
			(at 0 0 90)
			(layer "B.SilkS")
			(hide yes)
			(effects
				(font
					(size 1.27 1.27)
				)
				(justify mirror)
			)
		)
		(property "Value" ""
			(at 0 0 90)
			(layer "B.Fab")
			(effects
				(font
					(size 1.27 1.27)
				)
				(justify mirror)
			)
		)
		(duplicate_pad_numbers_are_jumpers no)
		(fp_line
			(start -1.524 0.762)
			(end 1.524 0.762)
			(stroke
				(width 0.1524)
				(type default)
			)
			(layer "B.SilkS")
		)
		(fp_line
			(start 1.524 0.762)
			(end 1.524 -0.762)
			(stroke
				(width 0.1524)
				(type default)
			)
			(layer "B.SilkS")
		)
		(fp_line
			(start -1.524 -0.762)
			(end -1.524 0.762)
			(stroke
				(width 0.1524)
				(type default)
			)
			(layer "B.SilkS")
		)
		(fp_line
			(start 1.524 -0.762)
			(end -1.524 -0.762)
			(stroke
				(width 0.1524)
				(type default)
			)
			(layer "B.SilkS")
		)
		(fp_line
			(start -1.1049 0.724916)
			(end -1.1049 -0.724916)
			(stroke
				(width 0.1)
				(type default)
			)
			(layer "B.Fab")
		)
		(fp_line
			(start 1.1049 0.724916)
			(end -1.1049 0.724916)
			(stroke
				(width 0.1)
				(type default)
			)
			(layer "B.Fab")
		)
		(fp_line
			(start -1.1049 -0.724916)
			(end 1.1049 -0.724916)
			(stroke
				(width 0.1)
				(type default)
			)
			(layer "B.Fab")
		)
		(fp_line
			(start 1.1049 -0.724916)
			(end 1.1049 0.724916)
			(stroke
				(width 0.1)
				(type default)
			)
			(layer "B.Fab")
		)
		(pad "1" smd rect
			(at 0.889 0 270)
			(size 1.016 1.27)
			(layers "B.Cu" "B.Mask" "B.Paste")
			(net "P12V_S3_AUX_CPU0_NVDIMM")
		)
		(pad "2" smd rect
			(at -0.889 0 270)
			(size 1.016 1.27)
			(layers "B.Cu" "B.Mask" "B.Paste")
			(net "GND")
		)
	)
	(footprint ""
		(layer "B.Cu")
		(at 369.055142 -357.667306 180)
		(property "Reference" "PC1421"
			(at 0 0 0)
			(layer "B.SilkS")
			(hide yes)
			(effects
				(font
					(size 1.27 1.27)
				)
				(justify mirror)
			)
		)
		(property "Value" ""
			(at 0 0 0)
			(layer "B.Fab")
			(effects
				(font
					(size 1.27 1.27)
				)
				(justify mirror)
			)
		)
		(duplicate_pad_numbers_are_jumpers no)
		(fp_line
			(start 0.7874 0.4064)
			(end 0.7874 -0.4064)
			(stroke
				(width 0.1524)
				(type default)
			)
			(layer "B.SilkS")
		)
		(fp_line
			(start 0.7874 -0.4064)
			(end -0.7874 -0.4064)
			(stroke
				(width 0.1524)
				(type default)
			)
			(layer "B.SilkS")
		)
		(fp_line
			(start -0.7874 0.4064)
			(end 0.7874 0.4064)
			(stroke
				(width 0.1524)
				(type default)
			)
			(layer "B.SilkS")
		)
		(fp_line
			(start -0.7874 -0.4064)
			(end -0.7874 0.4064)
			(stroke
				(width 0.1524)
				(type default)
			)
			(layer "B.SilkS")
		)
		(fp_line
			(start 0.67945 0.3048)
			(end 0.67945 -0.305054)
			(stroke
				(width 0.1)
				(type default)
			)
			(layer "B.Fab")
		)
		(fp_line
			(start 0.67945 -0.305054)
			(end 0.12065 -0.305054)
			(stroke
				(width 0.1)
				(type default)
			)
			(layer "B.Fab")
		)
		(fp_line
			(start 0.12065 0.3048)
			(end 0.67945 0.3048)
			(stroke
				(width 0.1)
				(type default)
			)
			(layer "B.Fab")
		)
		(fp_line
			(start 0.12065 0.2794)
			(end 0.12065 0.3048)
			(stroke
				(width 0.1)
				(type default)
			)
			(layer "B.Fab")
		)
		(fp_line
			(start 0.12065 -0.2794)
			(end -0.12065 -0.2794)
			(stroke
				(width 0.1)
				(type default)
			)
			(layer "B.Fab")
		)
		(fp_line
			(start 0.12065 -0.305054)
			(end 0.12065 -0.2794)
			(stroke
				(width 0.1)
				(type default)
			)
			(layer "B.Fab")
		)
		(fp_line
			(start -0.120396 0.3048)
			(end -0.120396 0.2794)
			(stroke
				(width 0.1)
				(type default)
			)
			(layer "B.Fab")
		)
		(fp_line
			(start -0.120396 0.2794)
			(end 0.12065 0.2794)
			(stroke
				(width 0.1)
				(type default)
			)
			(layer "B.Fab")
		)
		(fp_line
			(start -0.12065 -0.2794)
			(end -0.12065 -0.3048)
			(stroke
				(width 0.1)
				(type default)
			)
			(layer "B.Fab")
		)
		(fp_line
			(start -0.12065 -0.3048)
			(end -0.67945 -0.3048)
			(stroke
				(width 0.1)
				(type default)
			)
			(layer "B.Fab")
		)
		(fp_line
			(start -0.67945 0.3048)
			(end -0.120396 0.3048)
			(stroke
				(width 0.1)
				(type default)
			)
			(layer "B.Fab")
		)
		(fp_line
			(start -0.67945 -0.3048)
			(end -0.67945 0.3048)
			(stroke
				(width 0.1)
				(type default)
			)
			(layer "B.Fab")
		)
		(pad "1" smd circle
			(at 0.40005 0)
			(size 0 0)
			(layers "B.Cu" "B.Mask" "B.Paste")
			(net "SH_PVPP_HBM_CPU0_P")
		)
		(pad "2" smd circle
			(at -0.40005 0)
			(size 0 0)
			(layers "B.Cu" "B.Mask" "B.Paste")
			(net "SH_PVPP_HBM_CPU0_N")
		)
	)
)
